# S9S_MB_2U (Grand Teton) — schematic netlist excerpt (pin names and nets, part order shuffled) for the footprints in the layout excerpt that follows; sources: Cadence DE-HDL packaged netlist, KiCad conversion of 03242023_DA0F0TMBIJ0_F0T_Motherboard_J_brd_V01_OCP.brd

R4635  Q_RES  10K 1% CHIP  pkg 0402LF  page 248 : A = JTAG_BMC_SW_OE ; B = GND
PC272_P0_4  Q_CAP  2.2UF 10V 10% X6S  pkg C0402  page 268 : A = PVCCIN_CPU0_PVCC ; B = GND

(kicad_pcb
	(version 20260206)
	(generator "pcbnew")
	(generator_version "10.0")
	(general
		(thickness 1.6)
		(legacy_teardrops no)
	)
	(paper "A4")
	(title_block
		(title "03242023_DA0F0TMBIJ0_F0T_Motherboard_J_brd_V01_OCP.brd")
		(comment 1 "Grand Teton / footprints 2233-2234 of 6105")
	)
	(layers
		(0 "F.Cu" signal "TOP")
		(4 "In1.Cu" signal "GND")
		(6 "In2.Cu" signal "IN1")
		(8 "In3.Cu" signal "GND1")
		(10 "In4.Cu" signal "IN2")
		(12 "In5.Cu" signal "GND2")
		(14 "In6.Cu" signal "IN3")
		(16 "In7.Cu" signal "GND3")
		(18 "In8.Cu" signal "VCC")
		(20 "In9.Cu" signal "VCC1")
		(22 "In10.Cu" signal "GND4")
		(24 "In11.Cu" signal "IN4")
		(26 "In12.Cu" signal "GND5")
		(28 "In13.Cu" signal "IN5")
		(30 "In14.Cu" signal "GND6")
		(32 "In15.Cu" signal "IN6")
		(34 "In16.Cu" signal "GND7")
		(2 "B.Cu" signal "BOTTOM")
		(9 "F.Adhes" user "F.Adhesive")
		(11 "B.Adhes" user "B.Adhesive")
		(13 "F.Paste" user "Package Geometry/Pastemask Top")
		(15 "B.Paste" user "Package Geometry/Pastemask Bottom")
		(5 "F.SilkS" user "Ref Des/Silkscreen Top")
		(7 "B.SilkS" user "Ref Des/Silkscreen Bottom")
		(1 "F.Mask" user "Board Geometry/Soldermask Top")
		(3 "B.Mask" user "Board Geometry/Soldermask Bottom")
		(17 "Dwgs.User" user "User.Drawings")
		(19 "Cmts.User" user "User.Comments")
		(21 "Eco1.User" user "User.Eco1")
		(23 "Eco2.User" user "User.Eco2")
		(25 "Edge.Cuts" user "Board Geometry/Outline")
		(27 "Margin" user)
		(31 "F.CrtYd" user "Package Geometry/Place Bound Top")
		(29 "B.CrtYd" user "Package Geometry/Place Bound Bottom")
		(35 "F.Fab" user "Ref Des/Assembly Top")
		(33 "B.Fab" user "Ref Des/Assembly Bottom")
	)
	(footprint ""
		(layer "F.Cu")
		(at 365.844328 -333.525368 -90)
		(property "Reference" "PC272_P0_4"
			(at 0 0 270)
			(layer "F.SilkS")
			(hide yes)
			(effects
				(font
					(size 1.27 1.27)
				)
			)
		)
		(property "Value" ""
			(at 0 0 270)
			(layer "F.Fab")
			(effects
				(font
					(size 1.27 1.27)
				)
			)
		)
		(duplicate_pad_numbers_are_jumpers no)
		(fp_line
			(start -0.7874 0.4064)
			(end -0.7874 -0.4064)
			(stroke
				(width 0.1524)
				(type default)
			)
			(layer "F.SilkS")
		)
		(fp_line
			(start 0.7874 0.4064)
			(end -0.7874 0.4064)
			(stroke
				(width 0.1524)
				(type default)
			)
			(layer "F.SilkS")
		)
		(fp_line
			(start -0.7874 -0.4064)
			(end 0.7874 -0.4064)
			(stroke
				(width 0.1524)
				(type default)
			)
			(layer "F.SilkS")
		)
		(fp_line
			(start 0.7874 -0.4064)
			(end 0.7874 0.4064)
			(stroke
				(width 0.1524)
				(type default)
			)
			(layer "F.SilkS")
		)
		(fp_line
			(start -0.67945 0.3048)
			(end -0.67945 -0.305054)
			(stroke
				(width 0.1)
				(type default)
			)
			(layer "F.Fab")
		)
		(fp_line
			(start -0.12065 0.3048)
			(end -0.67945 0.3048)
			(stroke
				(width 0.1)
				(type default)
			)
			(layer "F.Fab")
		)
		(fp_line
			(start 0.120396 0.3048)
			(end 0.120396 0.2794)
			(stroke
				(width 0.1)
				(type default)
			)
			(layer "F.Fab")
		)
		(fp_line
			(start 0.67945 0.3048)
			(end 0.120396 0.3048)
			(stroke
				(width 0.1)
				(type default)
			)
			(layer "F.Fab")
		)
		(fp_line
			(start -0.12065 0.2794)
			(end -0.12065 0.3048)
			(stroke
				(width 0.1)
				(type default)
			)
			(layer "F.Fab")
		)
		(fp_line
			(start 0.120396 0.2794)
			(end -0.12065 0.2794)
			(stroke
				(width 0.1)
				(type default)
			)
			(layer "F.Fab")
		)
		(fp_line
			(start -0.12065 -0.2794)
			(end 0.12065 -0.2794)
			(stroke
				(width 0.1)
				(type default)
			)
			(layer "F.Fab")
		)
		(fp_line
			(start 0.12065 -0.2794)
			(end 0.12065 -0.3048)
			(stroke
				(width 0.1)
				(type default)
			)
			(layer "F.Fab")
		)
		(fp_line
			(start 0.12065 -0.3048)
			(end 0.67945 -0.3048)
			(stroke
				(width 0.1)
				(type default)
			)
			(layer "F.Fab")
		)
		(fp_line
			(start 0.67945 -0.3048)
			(end 0.67945 0.3048)
			(stroke
				(width 0.1)
				(type default)
			)
			(layer "F.Fab")
		)
		(fp_line
			(start -0.67945 -0.305054)
			(end -0.12065 -0.305054)
			(stroke
				(width 0.1)
				(type default)
			)
			(layer "F.Fab")
		)
		(fp_line
			(start -0.12065 -0.305054)
			(end -0.12065 -0.2794)
			(stroke
				(width 0.1)
				(type default)
			)
			(layer "F.Fab")
		)
		(pad "1" smd circle
			(at -0.40005 0 270)
			(size 0 0)
			(layers "F.Cu" "F.Mask" "F.Paste")
			(net "PVCCIN_CPU0_PVCC")
		)
		(pad "2" smd circle
			(at 0.40005 0 270)
			(size 0 0)
			(layers "F.Cu" "F.Mask" "F.Paste")
			(net "GND")
		)
	)
	(footprint ""
		(layer "F.Cu")
		(at 128.016 -60.416948)
		(property "Reference" "R4635"
			(at 0 0 0)
			(layer "F.SilkS")
			(hide yes)
			(effects
				(font
					(size 1.27 1.27)
				)
			)
		)
		(property "Value" ""
			(at 0 0 0)
			(layer "F.Fab")
			(effects
				(font
					(size 1.27 1.27)
				)
			)
		)
		(duplicate_pad_numbers_are_jumpers no)
		(fp_line
			(start -0.7874 -0.4064)
			(end 0.7874 -0.4064)
			(stroke
				(width 0.1524)
				(type default)
			)
			(layer "F.SilkS")
		)
		(fp_line
			(start -0.7874 0.4064)
			(end -0.7874 -0.4064)
			(stroke
				(width 0.1524)
				(type default)
			)
			(layer "F.SilkS")
		)
		(fp_line
			(start 0.7874 -0.4064)
			(end 0.7874 0.4064)
			(stroke
				(width 0.1524)
				(type default)
			)
			(layer "F.SilkS")
		)
		(fp_line
			(start 0.7874 0.4064)
			(end -0.7874 0.4064)
			(stroke
				(width 0.1524)
				(type default)
			)
			(layer "F.SilkS")
		)
		(fp_line
			(start -0.67945 -0.305054)
			(end -0.12065 -0.305054)
			(stroke
				(width 0.1)
				(type default)
			)
			(layer "F.Fab")
		)
		(fp_line
			(start -0.67945 0.3048)
			(end -0.67945 -0.305054)
			(stroke
				(width 0.1)
				(type default)
			)
			(layer "F.Fab")
		)
		(fp_line
			(start -0.12065 -0.305054)
			(end -0.12065 -0.2794)
			(stroke
				(width 0.1)
				(type default)
			)
			(layer "F.Fab")
		)
		(fp_line
			(start -0.12065 -0.2794)
			(end 0.12065 -0.2794)
			(stroke
				(width 0.1)
				(type default)
			)
			(layer "F.Fab")
		)
		(fp_line
			(start -0.12065 0.2794)
			(end -0.12065 0.3048)
			(stroke
				(width 0.1)
				(type default)
			)
			(layer "F.Fab")
		)
		(fp_line
			(start -0.12065 0.3048)
			(end -0.67945 0.3048)
			(stroke
				(width 0.1)
				(type default)
			)
			(layer "F.Fab")
		)
		(fp_line
			(start 0.120396 0.2794)
			(end -0.12065 0.2794)
			(stroke
				(width 0.1)
				(type default)
			)
			(layer "F.Fab")
		)
		(fp_line
			(start 0.120396 0.3048)
			(end 0.120396 0.2794)
			(stroke
				(width 0.1)
				(type default)
			)
			(layer "F.Fab")
		)
		(fp_line
			(start 0.12065 -0.3048)
			(end 0.67945 -0.3048)
			(stroke
				(width 0.1)
				(type default)
			)
			(layer "F.Fab")
		)
		(fp_line
			(start 0.12065 -0.2794)
			(end 0.12065 -0.3048)
			(stroke
				(width 0.1)
				(type default)
			)
			(layer "F.Fab")
		)
		(fp_line
			(start 0.67945 -0.3048)
			(end 0.67945 0.3048)
			(stroke
				(width 0.1)
				(type default)
			)
			(layer "F.Fab")
		)
		(fp_line
			(start 0.67945 0.3048)
			(end 0.120396 0.3048)
			(stroke
				(width 0.1)
				(type default)
			)
			(layer "F.Fab")
		)
		(pad "1" smd circle
			(at -0.40005 0)
			(size 0 0)
			(layers "F.Cu" "F.Mask" "F.Paste")
			(net "JTAG_BMC_SW_OE")
		)
		(pad "2" smd circle
			(at 0.40005 0)
			(size 0 0)
			(layers "F.Cu" "F.Mask" "F.Paste")
			(net "GND")
		)
	)
)
